FILE_TYPE = MULTI_PHYS_TABLE;

PART 'Q_CRYSTAL'

{========================================================================================}
:VALUE         | PACK_TYPE | MATERIAL | PART_NUMBER        = STANDARD        | LIFECYCLE      | PART_NUMBER   | JEDEC_TYPE                        | CLASS | DESCRIPTION                                | COMPONENT_TYPE | LEAD_LENGTH | DAY         ;
{========================================================================================}
 '30MHz'       | 'SM'      | 'IC'     | 'TMP_QBG630000103'(!) = 'End of Design' | 'End of Life'  | 'BG630000103' |'X_6X_EOL'| 'IC'  | 'XTAL SMD 30MHZ(+-30PPM,16PF)6X30000010'   | 'SMTOTHER'     | ''          | ''         
 '30MHz'       | 'SM'      | 'EMPTY'  | 'TMP_QBG630000103'(!) = 'End of Design' | 'End of Life'  | 'BG630000103' |'X_6X_EOL'| 'IO'  | 'XTAL SMD 30MHZ(+-30PPM,16PF)6X30000010'   | 'SMTOTHER'     | ''          | ''         
 '24.576MHZ'   | 'SM'      | 'IC'     | 'TMP_QBG624576465'(!) = ''              | 'End of Life'  | 'BG624576465' |'X_6X_EOL'| 'IC'  | 'XTAL SMD 24.576MHZ(+-30PPM)6X24500072'    | 'SMTOTHER'     | ''          | ''         
 '24.576MHZ'   | 'SM'      | 'EMPTY'  | 'TMP_QBG624576465'(!) = ''              | 'End of Life'  | 'BG624576465' |'X_6X_EOL'| 'IO'  | 'XTAL SMD 24.576MHZ(+-30PPM)6X24500072'    | 'SMTOTHER'     | ''          | ''         
 '18.432MHZ'   | 'SM'      | 'IC'     | 'TMP_QBG618432601'(!) = ''              | ''             | 'BG618432601' |'X_F8_H67'| 'IC'  | 'XTAL SMD 18.432 MHZ(+-30PPM,F81840002)'   | 'SMTOTHER'     | ''          | ''         
 '18.432MHZ'   | 'SM'      | 'EMPTY'  | 'TMP_QBG618432601'(!) = ''              | ''             | 'BG618432601' |'X_F8_H67'| 'IO'  | 'XTAL SMD 18.432 MHZ(+-30PPM,F81840002)'   | 'SMTOTHER'     | ''          | ''         
 '14.318MHZ'   | 'SM'      | 'IC'     | 'QN-BG614318Q25'(!) = 'End of Design' | 'End of Life'  | 'BG614318Q25' |'X_6XXA_EOL'| 'IC'  | 'XTAL SMD 14.318MHZ(+-20PPM,20PF)'         | 'SMTOTHER'     | ''          | ''         
 '14.318MHZ'   | 'SM'      | 'EMPTY'  | 'QN-BG614318Q25'(!) = 'End of Design' | 'End of Life'  | 'BG614318Q25' |'X_6XXA_EOL'| 'IO'  | 'XTAL SMD 14.318MHZ(+-20PPM,20PF)'         | 'SMTOTHER'     | ''          | ''         
 '25MHZ'       | 'SM'      | 'IC'     | 'QN-BG625000435'(!) = ''              | 'End of Life'  | 'BG625000435' |'X_HC49A_EOL'| 'IC'  | 'CRYSTAL SMD 25MHZ(+-30PPM,9C25000355)'    | 'SMTOTHER'     | ''          | ''         
 '25MHZ'       | 'SM'      | 'EMPTY'  | 'QN-BG625000435'(!) = ''              | 'End of Life'  | 'BG625000435' |'X_HC49A_EOL'| 'IO'  | 'CRYSTAL SMD 25MHZ(+-30PPM,9C25000355)'    | 'SMTOTHER'     | ''          | ''         
 '14.31818MHz' | 'SM'      | 'IC'     | 'BG614318S11'(!)   = ''              | 'End of Life'  | 'BG614318S11' |'X_HC49A_EOL'| 'IC'  | 'XTAL SMD 14.318MHZ(+-30PPM,9C14300040)LF' | 'SMTOTHER'     | ''          | '20100714' 
 '14.31818MHz' | 'SM'      | 'EMPTY'  | 'BG614318S11'(!)   = ''              | 'End of Life'  | 'BG614318S11' |'X_HC49A_EOL'| 'IO'  | 'XTAL SMD 14.318MHZ(+-30PPM,9C14300040)LF' | 'SMTOTHER'     | ''          | '20100714' 
 '50MHZ'       | 'SM'      | 'IC'     | 'BG650000003'(!)   = ''              | 'End of Life'    | 'BG650000003' |'X_7A_EOL'| 'IC'  | 'XTAL SMD 50MHZ(+-15PPM,16PF)7A50020001'   | 'SMTOTHER'     | ''          | '20110211' 
 '50MHZ'       | 'SM'      | 'EMPTY'  | 'BG650000003'(!)   = ''              | 'End of Life'    | 'BG650000003' |'X_7A_EOL'| 'IO'  | 'XTAL SMD 50MHZ(+-15PPM,16PF)7A50020001'   | 'SMTOTHER'     | ''          | '20110211' 
 '48MHZ'       | 'SMLF'    | 'IC'     | 'BG648000010'(!)   = 'End of Design' | 'End of Life'    | 'BG648000010' |'X_7A_EOL'| 'IC'  | 'XTAL SMD 48MHZ(+-20PPM,12PF)7A48000065'   | 'SMTOTHER'     | ''          | '2011/3/24'
 '48MHZ'       | 'SMLF'    | 'EMPTY'  | 'BG648000010'(!)   = 'End of Design' | 'End of Life'    | 'BG648000010' |'X_7A_EOL'| 'IO'  | 'XTAL SMD 48MHZ(+-20PPM,12PF)7A48000065'   | 'SMTOTHER'     | ''          | '2011/3/24'
 '6MHz'        | 'SMLF'    | 'IC'     | 'BG560000001'(!)   = ''              | 'End of Life'  | 'BG560000001' |'X_HC49A_EOL'| 'IC'  | 'CRYSTAL SMD 6MHZ(20PF+-30PPM0)9C06000077' | 'SMTOTHER'     | ''          | '20111209' 
 '6MHz'        | 'SMLF'    | 'EMPTY'  | 'BG560000001'(!)   = ''              | 'End of Life'  | 'BG560000001' |'X_HC49A_EOL'| 'IO'  | 'CRYSTAL SMD 6MHZ(20PF+-30PPM0)9C06000077' | 'SMTOTHER'     | ''          | '20111209' 
 '12MHz'       | 'SMLF'    | 'IC'     | 'BG612000009'(!)   = 'End of Design' | 'End of Life'  | 'BG612000009' |'X_HC49XA_EOL'| 'IC'  | 'XTAL 12MHZ(30PPM.20PF)ESB12.0000F20E35F'  | 'SMTOTHER'     | ''          | '20111209' 
 '12MHz'       | 'SMLF'    | 'EMPTY'  | 'BG612000009'(!)   = 'End of Design' | 'End of Life'  | 'BG612000009' |'X_HC49XA_EOL'| 'IO'  | 'XTAL 12MHZ(30PPM.20PF)ESB12.0000F20E35F'  | 'SMTOTHER'     | ''          | '20111209' 
 '12MHz'       | 'SMLF'    | 'IC'     | 'BG612000334'(!)   = 'End of Design' | 'End of Life'    | 'BG612000334' |'X_7A_EOL'| 'IC'  | 'XTAL SMD 12MHZ(+-30PPM,16PF)7A12000017'   | 'SMTOTHER'     | ''          | '20120109' 
 '12MHz'       | 'SMLF'    | 'EMPTY'  | 'BG612000334'(!)   = 'End of Design' | 'End of Life'    | 'BG612000334' |'X_7A_EOL'| 'IO'  | 'XTAL SMD 12MHZ(+-30PPM,16PF)7A12000017'   | 'SMTOTHER'     | ''          | '20120109' 
 '32.768KHZ'   | 'SMLF'    | 'IC'     | 'BG332768066'(!)   = ''              | ''             | 'BG332768066' |'X_2S_XTL721'| 'IC'  | 'XTAL SMD 32.768KHZ(20PPM,12.5PF)XTL721'   | 'SMTOTHER'     | ''          | '20120525' 
 '32.768KHZ'   | 'SMLF'    | 'EMPTY'  | 'BG332768066'(!)   = ''              | ''             | 'BG332768066' |'X_2S_XTL721'| 'IO'  | 'XTAL SMD 32.768KHZ(20PPM,12.5PF)XTL721'   | 'SMTOTHER'     | ''          | '20120525' 
 '32.768KHZ'   | 'SMLF'    | 'IC'     | 'BG332768453'(!)   = ''              | ''             | 'BG332768453' |'X_2S_FC145'| 'IC'  | 'CRYSTAL SMD 32.768KHZ(+-20PPM,12.5PF)'    | 'SMTOTHER'     | ''          | '20120712' 
 '32.768KHZ'   | 'SMLF'    | 'EMPTY'  | 'BG332768453'(!)   = ''              | ''             | 'BG332768453' |'X_2S_FC145'| 'IO'  | 'CRYSTAL SMD 32.768KHZ(+-20PPM,12.5PF)'    | 'SMTOTHER'     | ''          | '20120712' 
 '32.768KHZ'   | 'SMLF'    | 'IC'     | 'BG332768077'(!)   = 'End of Design' | 'Comp-Approve' | 'BG332768077' |'X_2S_XTL721'| 'IC'  | 'CRYSTAL SMD 32.768KHZ(+-20PPM,12.5PF)'    | 'SMTOTHER'     | ''          | '20120917' 
 '32.768KHZ'   | 'SMLF'    | 'EMPTY'  | 'BG332768077'(!)   = 'End of Design' | 'Comp-Approve' | 'BG332768077' |'X_2S_XTL721'| 'IO'  | 'CRYSTAL SMD 32.768KHZ(+-20PPM,12.5PF)'    | 'SMTOTHER'     | ''          | '20120917' 
 '32.768KHZ'   | 'SMLF'    | 'IC'     | 'BG332768111'(!)   = 'End of Design' | 'Comp-Approve' | 'BG332768111' |'X_2S_XTL721'| 'IC'  | 'CRYSTAL SMD 32.768KHZ(+-20PPM,12.5PF)'    | 'SMTOTHER'     | ''          | '20121218' 
 '32.768KHZ'   | 'SMLF'    | 'EMPTY'  | 'BG332768111'(!)   = 'End of Design' | 'Comp-Approve' | 'BG332768111' |'X_2S_XTL721'| 'IO'  | 'CRYSTAL SMD 32.768KHZ(+-20PPM,12.5PF)'    | 'SMTOTHER'     | ''          | '20121218' 
 '32.768KHZ'   | 'SMLF'    | 'IC'     | 'BG332768124'(!)   = ''              | ''             | 'BG332768124' |'X_2S_XTL721'| 'IC'  | 'CRYSTAL SMD 32.768KHZ(+-20PPM,12.5PF)'    | 'SMTOTHER'     | ''          | '20130924' 
 '32.768KHZ'   | 'SMLF'    | 'EMPTY'  | 'BG332768124'(!)   = ''              | ''             | 'BG332768124' |'X_2S_XTL721'| 'IO'  | 'CRYSTAL SMD 32.768KHZ(+-20PPM,12.5PF)'    | 'SMTOTHER'     | ''          | '20130924' 
 '25MHZ'       | 'SMLF'    | 'IC'     | 'BG625000082'(!)   = 'End of Design' | 'End of Life'  | 'BG625000082' |'X_HC49_EOL'| 'IC'  | 'XTAL SMD 25MHZ(20PPM,18PF)'               | 'SMTOTHER'     | ''          | '20140226' 
 '25MHZ'       | 'SMLF'    | 'EMPTY'  | 'BG625000082'(!)   = 'End of Design' | 'End of Life'  | 'BG625000082' |'X_HC49_EOL'| 'IO'  | 'XTAL SMD 25MHZ(20PPM,18PF)'               | 'SMTOTHER'     | ''          | '20140226' 
 '32.768KHZ'   | 'SMLF'    | 'IC'     | 'BG632768012'(!)   = 'End of Design' | 'Comp-Approve' | 'BG632768012' |'X_2S_XTL721'| 'IC'  | 'CRYSTAL SMD 32.768KHZ(+-20PPM,12.5PF)'    | 'SMTOTHER'     | ''          | '20141103' 
 '32.768KHZ'   | 'SMLF'    | 'EMPTY'  | 'BG632768012'(!)   = 'End of Design' | 'Comp-Approve' | 'BG632768012' |'X_2S_XTL721'| 'IO'  | 'CRYSTAL SMD 32.768KHZ(+-20PPM,12.5PF)'    | 'SMTOTHER'     | ''          | '20141103' 
 '32.768KHZ'   | 'SMLF'    | 'IC'     | 'BG332768232'(!)   = ''              | ''             | 'BG332768232' |'X_2S_1TJE125DP1A000M_4-1X1-5'| 'IC'  | 'XTAL 32.768KHZ(20PPM)1TJE125DP1A000M'     | 'SMTOTHER'     | ''          | '20141205' 
 '32.768KHZ'   | 'SMLF'    | 'EMPTY'  | 'BG332768232'(!)   = ''              | ''             | 'BG332768232' |'X_2S_1TJE125DP1A000M_4-1X1-5'| 'IO'  | 'XTAL 32.768KHZ(20PPM)1TJE125DP1A000M'     | 'SMTOTHER'     | ''          | '20141205' 
 '32.768KHZ'   | 'SMLF'    | 'IC'     | 'BG332768146'(!)   = 'End of Design' | 'P/N Release'  | 'BG332768146' |'X_2S_XTL721'| 'IC'  | 'XTAL SMD 32.768KHZ(20PPM,12.5PF)AEC'      | 'SMTOTHER'     | ''          | '20160426' 
 '32.768KHZ'   | 'SMLF'    | 'EMPTY'  | 'BG332768146'(!)   = 'End of Design' | 'P/N Release'  | 'BG332768146' |'X_2S_XTL721'| 'IO'  | 'XTAL SMD 32.768KHZ(20PPM,12.5PF)AEC'      | 'SMTOTHER'     | ''          | '20160426' 
 '32.768KHZ'   | 'SMLF'    | 'IC'     | 'BG332768149'(!)   = ''              | ''             | 'BG332768149' |'X_2S_AH03200013_3-2X1-5'| 'IC'  | 'XTAL SMD 32.768KHZ(12.5PF,20PPM)AEC'      | 'SMTOTHER'     | ''          | '20160516' 
 '32.768KHZ'   | 'SMLF'    | 'EMPTY'  | 'BG332768149'(!)   = ''              | ''             | 'BG332768149' |'X_2S_AH03200013_3-2X1-5'| 'IO'  | 'XTAL SMD 32.768KHZ(12.5PF,20PPM)AEC'      | 'SMTOTHER'     | ''          | '20160516' 
 '32.768KHZ'   | 'SMLF'    | 'IC'     | 'BG3327680C7'(!)   = 'End of Design' | 'End of Life'  | 'BG3327680C7' |'X_2S_ETST00327000JE_3-2X1-5_EOL'| 'IC'  | 'CRYSTAL SMD 32.768KHZ(+-20PPM,12.5PF)'    | 'SMTOTHER'     | ''          | '20160808' 
 '32.768KHZ'   | 'SMLF'    | 'EMPTY'  | 'BG3327680C7'(!)   = 'End of Design' | 'End of Life'  | 'BG3327680C7' |'X_2S_ETST00327000JE_3-2X1-5_EOL'| 'IO'  | 'CRYSTAL SMD 32.768KHZ(+-20PPM,12.5PF)'    | 'SMTOTHER'     | ''          | '20160808' 
 '32.768KHZ'   | 'SMLF'    | 'IC'     | 'BG332768152'(!)   = 'End of Design' | 'Comp-Approve' | 'BG332768152' |'X_2S_AH03200013_3-2X1-5'| 'IC'  | 'XTAL SMD 32.768KHZ(20PPM,7PF)AH03200001'  | 'SMTOTHER'     | ''          | '20160816' 
 '32.768KHZ'   | 'SMLF'    | 'EMPTY'  | 'BG332768152'(!)   = 'End of Design' | 'Comp-Approve' | 'BG332768152' |'X_2S_AH03200013_3-2X1-5'| 'IO'  | 'XTAL SMD 32.768KHZ(20PPM,7PF)AH03200001'  | 'SMTOTHER'     | ''          | '20160816' 
 '32.768KHZ'   | 'SMLF'    | 'IC'     | 'BG3327680C4'(!)   = 'End of Design' | 'End of Life'  | 'BG3327680C4' |'X_2S_ETST00327000JE_3-2X1-5_EOL'| 'IC'  | 'CRYSTAL SMD 32.768KHZ(+-20PPM,12.5PF)'    | 'SMTOTHER'     | ''          | '20160923' 
 '32.768KHZ'   | 'SMLF'    | 'EMPTY'  | 'BG3327680C4'(!)   = 'End of Design' | 'End of Life'  | 'BG3327680C4' |'X_2S_ETST00327000JE_3-2X1-5_EOL'| 'IO'  | 'CRYSTAL SMD 32.768KHZ(+-20PPM,12.5PF)'    | 'SMTOTHER'     | ''          | '20160923' 
 '32.768KHZ'   | 'SMLF'    | 'IC'     | 'BG332768133'(!)   = ''              | ''             | 'BG332768133' |'X_2S_XTL721'| 'IC'  | 'XTAL 32.768KHZ(10PPM,12.5PF)9H03270039'   | 'SMTOTHER'     | ''          | '20170517' 
 '32.768KHZ'   | 'SMLF'    | 'EMPTY'  | 'BG332768133'(!)   = ''              | ''             | 'BG332768133' |'X_2S_XTL721'| 'IO'  | 'XTAL 32.768KHZ(10PPM,12.5PF)9H03270039'   | 'SMTOTHER'     | ''          | '20170517' 
 '32.768KHZ'   | 'SMLF'    | 'IC'     | 'BG332768084'(!)   = 'End of Design' | 'Comp-Approve' | 'BG332768084' |'X_2S_9H03200012_2X1-2'| 'IC'  | 'CRYSTAL SMD 32.768KHZ(+-20PPM,12.5PF)'    | 'SMTOTHER'     | ''          | '20171218' 
 '32.768KHZ'   | 'SMLF'    | 'EMPTY'  | 'BG332768084'(!)   = 'End of Design' | 'Comp-Approve' | 'BG332768084' |'X_2S_9H03200012_2X1-2'| 'IO'  | 'CRYSTAL SMD 32.768KHZ(+-20PPM,12.5PF)'    | 'SMTOTHER'     | ''          | '20171218' 
 '32.768KHZ'   | 'SMLF'    | 'IC'     | 'BG3327680B4'(!)   = 'End of Design' | 'Comp-Approve' | 'BG3327680B4' |'X_2S_XTL721'| 'IC'  | 'XTAL 32.768KHZ(+-20PPM,9PF)X1A0001410002' | 'SMTOTHER'     | ''          | '20180402' 
 '32.768KHZ'   | 'SMLF'    | 'EMPTY'  | 'BG3327680B4'(!)   = 'End of Design' | 'Comp-Approve' | 'BG3327680B4' |'X_2S_XTL721'| 'IO'  | 'XTAL 32.768KHZ(+-20PPM,9PF)X1A0001410002' | 'SMTOTHER'     | ''          | '20180402' 
 '32.768KHZ'   | 'SMLF'    | 'IC'     | 'BG332768144'(!)   = 'End of Design' | 'Comp-Approve' | 'BG332768144' |'X_2S_XTL721'| 'IC'  | 'XTAL32.768KHZ(10PPM,12.5PF)9H03200051'    | 'SMTOTHER'     | ''          | '20191017' 
 '32.768KHZ'   | 'SMLF'    | 'EMPTY'  | 'BG332768144'(!)   = 'End of Design' | 'Comp-Approve' | 'BG332768144' |'X_2S_XTL721'| 'IO'  | 'XTAL32.768KHZ(10PPM,12.5PF)9H03200051'    | 'SMTOTHER'     | ''          | '20191017' 
 '12MHZ'       | 'SMLF'    | 'IC'     | 'BG612000004'(!)   = ''              | 'End of Life'  | 'BG612000004' |'X_HC49A_EOL'| 'IC'  | 'XTAL 12MHZ(+-30PPM)9C12000065'            | 'SMTOTHER'     | ''          | '20191030' 
 '12MHZ'       | 'SMLF'    | 'EMPTY'  | 'BG612000004'(!)   = ''              | 'End of Life'  | 'BG612000004' |'X_HC49A_EOL'| 'IO'  | 'XTAL 12MHZ(+-30PPM)9C12000065'            | 'SMTOTHER'     | ''          | '20191030' 
 '32.768KHZ'   | 'SMLF'    | 'IC'     | 'BG332768142'(!)   = ''              | ''             | 'BG332768142' |'X_2S_XTL721'| 'IC'  | 'XTAL 32.768KHZ(10PPM,12.5PF)X1A000141000' | 'SMTOTHER'     | ''          | '20200225' 
 '32.768KHZ'   | 'SMLF'    | 'EMPTY'  | 'BG332768142'(!)   = ''              | ''             | 'BG332768142' |'X_2S_XTL721'| 'IO'  | 'XTAL 32.768KHZ(10PPM,12.5PF)X1A000141000' | 'SMTOTHER'     | ''          | '20200225' 
 '32.768KHZ'   | 'SMLF'    | 'IC'     | 'BG332768132'(!)   = ''              | ''             | 'BG332768132' |'X_2S_AH03200013_3-2X1-5_H36'| 'IC'  | 'XTAL SMD 32.768KHZ 12.5PF EXS00A-MU00503' | 'SMTOTHER'     | ''          | '20200714' 
 '32.768KHZ'   | 'SMLF'    | 'EMPTY'  | 'BG332768132'(!)   = ''              | ''             | 'BG332768132' |'X_2S_AH03200013_3-2X1-5_H36'| 'IO'  | 'XTAL SMD 32.768KHZ 12.5PF EXS00A-MU00503' | 'SMTOTHER'     | ''          | '20200714' 
 '8MHZ'        | 'SMLF'    | 'IC'     | 'BG580000027'(!)   = ''              | ''             | 'BG580000027' |'X_2S_STD-CSK-3_5X3-2'| 'IC'  | 'XTAL 8MHZ(8PF,+-20PPM)  STD-CSK-3'        | 'SMTOTHER'     | ''          | '20210316' 
 '8MHZ'        | 'SMLF'    | 'EMPTY'  | 'BG580000027'(!)   = ''              | ''             | 'BG580000027' |'X_2S_STD-CSK-3_5X3-2'| 'IO'  | 'XTAL 8MHZ(8PF,+-20PPM)  STD-CSK-3'        | 'SMTOTHER'     | ''          | '20210316' 
 '12MHZ'       | 'SMLF'    | 'IC'     | 'BG6120000D0'(!)   = ''               | ''               | 'BG6120000D0' |'X_2S_GC1200037_11-7X4-8'| 'IC'  | 'XTAL SMD 12MHZ(+-30PPM, 20PF)GC1200037'   | 'SMTOTHER'     | ''          | '20211018' 
 '12MHZ'       | 'SMLF'    | 'EMPTY'  | 'BG6120000D0'(!)   = ''               | ''               | 'BG6120000D0' |'X_2S_GC1200037_11-7X4-8'| 'IO'  | 'XTAL SMD 12MHZ(+-30PPM, 20PF)GC1200037'   | 'SMTOTHER'     | ''          | '20211018' 

END_PART

END.

